(kicad_pcb
	(version 20241229)
	(generator "pcbnew")
	(generator_version "9.0")
	(general
		(thickness 1.62)
		(legacy_teardrops no)
	)
	(paper "A4")
	(title_block
		(title "OCuLink to 10GbE adapter")
		(date "2026-02-23")
		(rev "1.1.0")
		(company "Antmicro Ltd")
		(comment 1 "www.antmicro.com")
		(comment 9 "footprints 373-378 of 510")
	)
	(layers
		(0 "F.Cu" signal)
		(4 "In1.Cu" signal)
		(6 "In2.Cu" signal)
		(8 "In3.Cu" signal)
		(10 "In4.Cu" signal)
		(12 "In5.Cu" signal)
		(14 "In6.Cu" signal)
		(2 "B.Cu" signal)
		(9 "F.Adhes" user "F.Adhesive")
		(11 "B.Adhes" user "B.Adhesive")
		(13 "F.Paste" user)
		(15 "B.Paste" user)
		(5 "F.SilkS" user "F.Silkscreen")
		(7 "B.SilkS" user "B.Silkscreen")
		(1 "F.Mask" user)
		(3 "B.Mask" user)
		(17 "Dwgs.User" user "User.Drawings")
		(19 "Cmts.User" user "User.Comments")
		(21 "Eco1.User" user "User.Eco1")
		(23 "Eco2.User" user "User.Eco2")
		(25 "Edge.Cuts" user)
		(27 "Margin" user)
		(31 "F.CrtYd" user "F.Courtyard")
		(29 "B.CrtYd" user "B.Courtyard")
		(35 "F.Fab" user)
		(33 "B.Fab" user)
	)
	(footprint "antmicro-footprints:C_0402_1005Metric"
		(layer "B.Cu")
		(at 88.225 100.15 90)
		(descr "Capacitor SMD 0402")
		(tags "capacitor SMD 0402")
		(property "Reference" "C91"
			(at 9.87 -0.409843 90)
			(layer "B.SilkS")
			(effects
				(font
					(size 0.7 0.7)
					(thickness 0.15)
				)
				(justify right top mirror)
			)
		)
		(property "Value" "C_1u_25V_0402"
			(at -1.022927 -2.155213 90)
			(layer "B.Fab")
			(hide yes)
			(effects
				(font
					(size 0.7 0.7)
					(thickness 0.15)
				)
				(justify right top mirror)
			)
		)
		(property "Datasheet" "https://www.murata.com/products/productdetail?partno=GRM155R61E105KE11%23"
			(at 0 0 90)
			(layer "B.Fab")
			(hide yes)
			(effects
				(font
					(size 1.27 1.27)
					(thickness 0.15)
				)
				(justify mirror)
			)
		)
		(property "Description" "SMD Multilayer Ceramic Capacitor, 1 µF, 25 V, 0402 [1005 Metric], ± 10%, X5R, GRM Series"
			(at 0 0 90)
			(layer "B.Fab")
			(hide yes)
			(effects
				(font
					(size 1.27 1.27)
					(thickness 0.15)
				)
				(justify mirror)
			)
		)
		(property "MPN" "GRM155R61E105KE11J"
			(at 0 0 90)
			(unlocked yes)
			(layer "B.Fab")
			(hide yes)
			(effects
				(font
					(size 1 1)
					(thickness 0.15)
				)
				(justify mirror)
			)
		)
		(property "Manufacturer" "Murata"
			(at 0 0 90)
			(unlocked yes)
			(layer "B.Fab")
			(hide yes)
			(effects
				(font
					(size 1 1)
					(thickness 0.15)
				)
				(justify mirror)
			)
		)
		(property "License" "Apache-2.0"
			(at 0 0 90)
			(unlocked yes)
			(layer "B.Fab")
			(hide yes)
			(effects
				(font
					(size 1 1)
					(thickness 0.15)
				)
				(justify mirror)
			)
		)
		(property "Author" "Antmicro"
			(at 0 0 90)
			(unlocked yes)
			(layer "B.Fab")
			(hide yes)
			(effects
				(font
					(size 1 1)
					(thickness 0.15)
				)
				(justify mirror)
			)
		)
		(property "Val" "1u"
			(at 0 0 90)
			(unlocked yes)
			(layer "B.Fab")
			(hide yes)
			(effects
				(font
					(size 1 1)
					(thickness 0.15)
				)
				(justify mirror)
			)
		)
		(property "Voltage" "25V"
			(at 0 0 90)
			(unlocked yes)
			(layer "B.Fab")
			(hide yes)
			(effects
				(font
					(size 1 1)
					(thickness 0.15)
				)
				(justify mirror)
			)
		)
		(property "Dielectric" "X5R"
			(at 0 0 90)
			(unlocked yes)
			(layer "B.Fab")
			(hide yes)
			(effects
				(font
					(size 1 1)
					(thickness 0.15)
				)
				(justify mirror)
			)
		)
		(sheetname "/X710-AT2 power/")
		(sheetfile "x710-at2-power.kicad_sch")
		(attr smd)
		(fp_rect
			(start -0.925 0.47)
			(end 0.925 -0.47)
			(stroke
				(width 0.05)
				(type default)
			)
			(fill no)
			(layer "B.CrtYd")
		)
		(fp_line
			(start 0.504 -0.248)
			(end -0.494 -0.248)
			(stroke
				(width 0.15)
				(type solid)
			)
			(layer "B.Fab")
		)
		(fp_line
			(start -0.494 -0.248)
			(end -0.494 0.25)
			(stroke
				(width 0.15)
				(type solid)
			)
			(layer "B.Fab")
		)
		(fp_line
			(start 0.504 0.25)
			(end 0.504 -0.248)
			(stroke
				(width 0.15)
				(type solid)
			)
			(layer "B.Fab")
		)
		(fp_line
			(start -0.494 0.25)
			(end 0.504 0.25)
			(stroke
				(width 0.15)
				(type solid)
			)
			(layer "B.Fab")
		)
		(pad "1" smd roundrect
			(at -0.48 0 90)
			(size 0.59 0.64)
			(layers "B.Cu" "B.Mask" "B.Paste")
			(roundrect_rratio 0.25)
			(net 28 "GND")
			(pintype "passive")
		)
		(pad "2" smd roundrect
			(at 0.48 0 90)
			(size 0.59 0.64)
			(layers "B.Cu" "B.Mask" "B.Paste")
			(roundrect_rratio 0.25)
			(net 1 "VCCA")
			(pintype "passive")
		)
	)
	(footprint "antmicro-footprints:C_0402_1005Metric"
		(layer "B.Cu")
		(at 86.225 96.45 90)
		(descr "Capacitor SMD 0402")
		(tags "capacitor SMD 0402")
		(property "Reference" "C105"
			(at 11.58 -0.432343 90)
			(layer "B.SilkS")
			(effects
				(font
					(size 0.7 0.7)
					(thickness 0.15)
				)
				(justify right top mirror)
			)
		)
		(property "Value" "C_1u_25V_0402"
			(at -1.022927 -2.155213 90)
			(layer "B.Fab")
			(hide yes)
			(effects
				(font
					(size 0.7 0.7)
					(thickness 0.15)
				)
				(justify right top mirror)
			)
		)
		(property "Datasheet" "https://www.murata.com/products/productdetail?partno=GRM155R61E105KE11%23"
			(at 0 0 90)
			(layer "B.Fab")
			(hide yes)
			(effects
				(font
					(size 1.27 1.27)
					(thickness 0.15)
				)
				(justify mirror)
			)
		)
		(property "Description" "SMD Multilayer Ceramic Capacitor, 1 µF, 25 V, 0402 [1005 Metric], ± 10%, X5R, GRM Series"
			(at 0 0 90)
			(layer "B.Fab")
			(hide yes)
			(effects
				(font
					(size 1.27 1.27)
					(thickness 0.15)
				)
				(justify mirror)
			)
		)
		(property "MPN" "GRM155R61E105KE11J"
			(at 0 0 90)
			(unlocked yes)
			(layer "B.Fab")
			(hide yes)
			(effects
				(font
					(size 1 1)
					(thickness 0.15)
				)
				(justify mirror)
			)
		)
		(property "Manufacturer" "Murata"
			(at 0 0 90)
			(unlocked yes)
			(layer "B.Fab")
			(hide yes)
			(effects
				(font
					(size 1 1)
					(thickness 0.15)
				)
				(justify mirror)
			)
		)
		(property "License" "Apache-2.0"
			(at 0 0 90)
			(unlocked yes)
			(layer "B.Fab")
			(hide yes)
			(effects
				(font
					(size 1 1)
					(thickness 0.15)
				)
				(justify mirror)
			)
		)
		(property "Author" "Antmicro"
			(at 0 0 90)
			(unlocked yes)
			(layer "B.Fab")
			(hide yes)
			(effects
				(font
					(size 1 1)
					(thickness 0.15)
				)
				(justify mirror)
			)
		)
		(property "Val" "1u"
			(at 0 0 90)
			(unlocked yes)
			(layer "B.Fab")
			(hide yes)
			(effects
				(font
					(size 1 1)
					(thickness 0.15)
				)
				(justify mirror)
			)
		)
		(property "Voltage" "25V"
			(at 0 0 90)
			(unlocked yes)
			(layer "B.Fab")
			(hide yes)
			(effects
				(font
					(size 1 1)
					(thickness 0.15)
				)
				(justify mirror)
			)
		)
		(property "Dielectric" "X5R"
			(at 0 0 90)
			(unlocked yes)
			(layer "B.Fab")
			(hide yes)
			(effects
				(font
					(size 1 1)
					(thickness 0.15)
				)
				(justify mirror)
			)
		)
		(sheetname "/X710-AT2 power/")
		(sheetfile "x710-at2-power.kicad_sch")
		(attr smd)
		(fp_rect
			(start -0.925 0.47)
			(end 0.925 -0.47)
			(stroke
				(width 0.05)
				(type default)
			)
			(fill no)
			(layer "B.CrtYd")
		)
		(fp_line
			(start 0.504 -0.248)
			(end -0.494 -0.248)
			(stroke
				(width 0.15)
				(type solid)
			)
			(layer "B.Fab")
		)
		(fp_line
			(start -0.494 -0.248)
			(end -0.494 0.25)
			(stroke
				(width 0.15)
				(type solid)
			)
			(layer "B.Fab")
		)
		(fp_line
			(start 0.504 0.25)
			(end 0.504 -0.248)
			(stroke
				(width 0.15)
				(type solid)
			)
			(layer "B.Fab")
		)
		(fp_line
			(start -0.494 0.25)
			(end 0.504 0.25)
			(stroke
				(width 0.15)
				(type solid)
			)
			(layer "B.Fab")
		)
		(pad "1" smd roundrect
			(at -0.48 0 90)
			(size 0.59 0.64)
			(layers "B.Cu" "B.Mask" "B.Paste")
			(roundrect_rratio 0.25)
			(net 28 "GND")
			(pintype "passive")
		)
		(pad "2" smd roundrect
			(at 0.48 0 90)
			(size 0.59 0.64)
			(layers "B.Cu" "B.Mask" "B.Paste")
			(roundrect_rratio 0.25)
			(net 9 "VCCD")
			(pintype "passive")
		)
	)
	(footprint "antmicro-footprints:C_0402_1005Metric"
		(layer "B.Cu")
		(at 92.8 113.610001 180)
		(descr "Capacitor SMD 0402")
		(tags "capacitor SMD 0402")
		(property "Reference" "C75"
			(at -1.18 -2.539999 0)
			(layer "B.SilkS")
			(effects
				(font
					(size 0.7 0.7)
					(thickness 0.15)
				)
				(justify left bottom mirror)
			)
		)
		(property "Value" "C_100n_0402"
			(at -1.022927 -2.155213 0)
			(layer "B.Fab")
			(hide yes)
			(effects
				(font
					(size 0.7 0.7)
					(thickness 0.15)
				)
				(justify left bottom mirror)
			)
		)
		(property "Datasheet" "https://www.murata.com/products/productdetail?partno=GRM155R61H104KE14%23"
			(at 0 0 0)
			(layer "B.Fab")
			(hide yes)
			(effects
				(font
					(size 1.27 1.27)
					(thickness 0.15)
				)
				(justify mirror)
			)
		)
		(property "Description" "SMD Multilayer Ceramic Capacitor, 0.1 µF, 50 V, 0402 [1005 Metric], ± 10%, X5R, GRM Series"
			(at 0 0 0)
			(layer "B.Fab")
			(hide yes)
			(effects
				(font
					(size 1.27 1.27)
					(thickness 0.15)
				)
				(justify mirror)
			)
		)
		(property "MPN" "GRM155R61H104KE14D"
			(at 0 0 180)
			(unlocked yes)
			(layer "B.Fab")
			(hide yes)
			(effects
				(font
					(size 1 1)
					(thickness 0.15)
				)
				(justify mirror)
			)
		)
		(property "Val" "100n"
			(at 0 0 180)
			(unlocked yes)
			(layer "B.Fab")
			(hide yes)
			(effects
				(font
					(size 1 1)
					(thickness 0.15)
				)
				(justify mirror)
			)
		)
		(property "Voltage" "50V"
			(at 0 0 180)
			(unlocked yes)
			(layer "B.Fab")
			(hide yes)
			(effects
				(font
					(size 1 1)
					(thickness 0.15)
				)
				(justify mirror)
			)
		)
		(property "Dielectric" "X5R"
			(at 0 0 180)
			(unlocked yes)
			(layer "B.Fab")
			(hide yes)
			(effects
				(font
					(size 1 1)
					(thickness 0.15)
				)
				(justify mirror)
			)
		)
		(property "Manufacturer" "Murata"
			(at 0 0 180)
			(unlocked yes)
			(layer "B.Fab")
			(hide yes)
			(effects
				(font
					(size 1 1)
					(thickness 0.15)
				)
				(justify mirror)
			)
		)
		(property "License" "Apache-2.0"
			(at 0 0 180)
			(unlocked yes)
			(layer "B.Fab")
			(hide yes)
			(effects
				(font
					(size 1 1)
					(thickness 0.15)
				)
				(justify mirror)
			)
		)
		(property "Author" "Antmicro"
			(at 0 0 180)
			(unlocked yes)
			(layer "B.Fab")
			(hide yes)
			(effects
				(font
					(size 1 1)
					(thickness 0.15)
				)
				(justify mirror)
			)
		)
		(sheetname "/X710-AT2 Misc/")
		(sheetfile "x710-at2-mics.kicad_sch")
		(attr smd)
		(fp_rect
			(start -0.925 0.47)
			(end 0.925 -0.47)
			(stroke
				(width 0.05)
				(type default)
			)
			(fill no)
			(layer "B.CrtYd")
		)
		(fp_line
			(start 0.504 0.25)
			(end 0.504 -0.248)
			(stroke
				(width 0.15)
				(type solid)
			)
			(layer "B.Fab")
		)
		(fp_line
			(start 0.504 -0.248)
			(end -0.494 -0.248)
			(stroke
				(width 0.15)
				(type solid)
			)
			(layer "B.Fab")
		)
		(fp_line
			(start -0.494 0.25)
			(end 0.504 0.25)
			(stroke
				(width 0.15)
				(type solid)
			)
			(layer "B.Fab")
		)
		(fp_line
			(start -0.494 -0.248)
			(end -0.494 0.25)
			(stroke
				(width 0.15)
				(type solid)
			)
			(layer "B.Fab")
		)
		(pad "1" smd roundrect
			(at -0.48 0 180)
			(size 0.59 0.64)
			(layers "B.Cu" "B.Mask" "B.Paste")
			(roundrect_rratio 0.25)
			(net 28 "GND")
			(pintype "passive")
		)
		(pad "2" smd roundrect
			(at 0.48 0 180)
			(size 0.59 0.64)
			(layers "B.Cu" "B.Mask" "B.Paste")
			(roundrect_rratio 0.25)
			(net 7 "+3V3")
			(pintype "passive")
		)
	)
	(footprint "antmicro-footprints:C_0402_1005Metric"
		(layer "B.Cu")
		(at 73.48 145.339998 -90)
		(descr "Capacitor SMD 0402")
		(tags "capacitor SMD 0402")
		(property "Reference" "C49"
			(at -2.939998 -0.46 90)
			(layer "B.SilkS")
			(effects
				(font
					(size 0.7 0.7)
					(thickness 0.15)
				)
				(justify left bottom mirror)
			)
		)
		(property "Value" "C_470p_0402"
			(at -1.022927 -2.155213 90)
			(layer "B.Fab")
			(hide yes)
			(effects
				(font
					(size 0.7 0.7)
					(thickness 0.15)
				)
				(justify left bottom mirror)
			)
		)
		(property "Datasheet" "https://www.passivecomponent.com/wp-content/uploads/datasheet/WTC_MLCC_General_Purpose.pdf"
			(at 0 0 90)
			(layer "B.Fab")
			(hide yes)
			(effects
				(font
					(size 1.27 1.27)
					(thickness 0.15)
				)
				(justify mirror)
			)
		)
		(property "Description" "SMD Multilayer Ceramic Capacitor, General Purpose, 470 pF, 25 V, 0402 [1005 Metric], ± 10%, X7R"
			(at 0 0 90)
			(layer "B.Fab")
			(hide yes)
			(effects
				(font
					(size 1.27 1.27)
					(thickness 0.15)
				)
				(justify mirror)
			)
		)
		(property "MPN" "0402B471K250CT"
			(at 0 0 270)
			(unlocked yes)
			(layer "B.Fab")
			(hide yes)
			(effects
				(font
					(size 1 1)
					(thickness 0.15)
				)
				(justify mirror)
			)
		)
		(property "Manufacturer" "Walsin"
			(at 0 0 270)
			(unlocked yes)
			(layer "B.Fab")
			(hide yes)
			(effects
				(font
					(size 1 1)
					(thickness 0.15)
				)
				(justify mirror)
			)
		)
		(property "License" "Apache-2.0"
			(at 0 0 270)
			(unlocked yes)
			(layer "B.Fab")
			(hide yes)
			(effects
				(font
					(size 1 1)
					(thickness 0.15)
				)
				(justify mirror)
			)
		)
		(property "Author" "Antmicro"
			(at 0 0 270)
			(unlocked yes)
			(layer "B.Fab")
			(hide yes)
			(effects
				(font
					(size 1 1)
					(thickness 0.15)
				)
				(justify mirror)
			)
		)
		(property "Val" "470p"
			(at 0 0 270)
			(unlocked yes)
			(layer "B.Fab")
			(hide yes)
			(effects
				(font
					(size 1 1)
					(thickness 0.15)
				)
				(justify mirror)
			)
		)
		(property "Voltage" "25V"
			(at 0 0 270)
			(unlocked yes)
			(layer "B.Fab")
			(hide yes)
			(effects
				(font
					(size 1 1)
					(thickness 0.15)
				)
				(justify mirror)
			)
		)
		(property "Dielectric" "X7R"
			(at 0 0 270)
			(unlocked yes)
			(layer "B.Fab")
			(hide yes)
			(effects
				(font
					(size 1 1)
					(thickness 0.15)
				)
				(justify mirror)
			)
		)
		(sheetname "/2xRJ45/")
		(sheetfile "2xrj45.kicad_sch")
		(attr smd)
		(fp_rect
			(start -0.925 0.47)
			(end 0.925 -0.47)
			(stroke
				(width 0.05)
				(type default)
			)
			(fill no)
			(layer "B.CrtYd")
		)
		(fp_line
			(start -0.494 0.25)
			(end 0.504 0.25)
			(stroke
				(width 0.15)
				(type solid)
			)
			(layer "B.Fab")
		)
		(fp_line
			(start 0.504 0.25)
			(end 0.504 -0.248)
			(stroke
				(width 0.15)
				(type solid)
			)
			(layer "B.Fab")
		)
		(fp_line
			(start -0.494 -0.248)
			(end -0.494 0.25)
			(stroke
				(width 0.15)
				(type solid)
			)
			(layer "B.Fab")
		)
		(fp_line
			(start 0.504 -0.248)
			(end -0.494 -0.248)
			(stroke
				(width 0.15)
				(type solid)
			)
			(layer "B.Fab")
		)
		(pad "1" smd roundrect
			(at -0.48 0 270)
			(size 0.59 0.64)
			(layers "B.Cu" "B.Mask" "B.Paste")
			(roundrect_rratio 0.25)
			(net 28 "GND")
			(pintype "passive")
		)
		(pad "2" smd roundrect
			(at 0.48 0 270)
			(size 0.59 0.64)
			(layers "B.Cu" "B.Mask" "B.Paste")
			(roundrect_rratio 0.25)
			(net 53 "Net-(J3-LED_YG_G-)")
			(pintype "passive")
		)
	)
	(footprint "antmicro-footprints:TP_SMD_0.75mm"
		(layer "B.Cu")
		(at 87.725 107.65 90)
		(property "Reference" "TP11"
			(at -2.13 0.505 90)
			(layer "B.SilkS")
			(effects
				(font
					(size 0.7 0.7)
					(thickness 0.15)
				)
				(justify right top mirror)
			)
		)
		(property "Value" "TP_0.75mm_SMD"
			(at 0 -1.2 90)
			(layer "B.Fab")
			(hide yes)
			(effects
				(font
					(size 0.7 0.7)
					(thickness 0.15)
				)
				(justify right top mirror)
			)
		)
		(property "Description" "SMT test point"
			(at 0 0 90)
			(layer "B.Fab")
			(hide yes)
			(effects
				(font
					(size 1.27 1.27)
					(thickness 0.15)
				)
				(justify mirror)
			)
		)
		(property "MPN" ""
			(at 0 0 90)
			(unlocked yes)
			(layer "B.Fab")
			(hide yes)
			(effects
				(font
					(size 1 1)
					(thickness 0.15)
				)
				(justify mirror)
			)
		)
		(property "Manufacturer" ""
			(at 0 0 90)
			(unlocked yes)
			(layer "B.Fab")
			(hide yes)
			(effects
				(font
					(size 1 1)
					(thickness 0.15)
				)
				(justify mirror)
			)
		)
		(property "Author" "Antmicro"
			(at 0 0 90)
			(unlocked yes)
			(layer "B.Fab")
			(hide yes)
			(effects
				(font
					(size 1 1)
					(thickness 0.15)
				)
				(justify mirror)
			)
		)
		(property "License" "Apache-2.0"
			(at 0 0 90)
			(unlocked yes)
			(layer "B.Fab")
			(hide yes)
			(effects
				(font
					(size 1 1)
					(thickness 0.15)
				)
				(justify mirror)
			)
		)
		(sheetname "/X710-AT2 Misc/")
		(sheetfile "x710-at2-mics.kicad_sch")
		(attr exclude_from_pos_files exclude_from_bom)
		(fp_circle
			(center 0 0)
			(end 0.475 0)
			(stroke
				(width 0.05)
				(type default)
			)
			(fill no)
			(layer "B.CrtYd")
		)
		(pad "1" smd circle
			(at 0 0 90)
			(size 0.75 0.75)
			(layers "B.Cu" "B.Mask")
			(net 135 "/X710-AT2 Misc/PHY_TMS")
			(pinfunction "1")
			(pintype "passive")
		)
	)
	(footprint "antmicro-footprints:TP_SMD_0.75mm"
		(layer "B.Cu")
		(at 61.925 84.775001 180)
		(property "Reference" "TP38"
			(at 0 0.6 0)
			(layer "B.SilkS")
			(hide yes)
			(effects
				(font
					(size 0.7 0.7)
					(thickness 0.15)
				)
				(justify left bottom mirror)
			)
		)
		(property "Value" "TP_0.75mm_SMD"
			(at 0 -1.2 0)
			(layer "B.Fab")
			(hide yes)
			(effects
				(font
					(size 0.7 0.7)
					(thickness 0.15)
				)
				(justify left bottom mirror)
			)
		)
		(property "Description" "SMT test point"
			(at 0 0 0)
			(layer "B.Fab")
			(hide yes)
			(effects
				(font
					(size 1.27 1.27)
					(thickness 0.15)
				)
				(justify mirror)
			)
		)
		(property "MPN" ""
			(at 0 0 0)
			(unlocked yes)
			(layer "B.Fab")
			(hide yes)
			(effects
				(font
					(size 1 1)
					(thickness 0.15)
				)
				(justify mirror)
			)
		)
		(property "Manufacturer" ""
			(at 0 0 0)
			(unlocked yes)
			(layer "B.Fab")
			(hide yes)
			(effects
				(font
					(size 1 1)
					(thickness 0.15)
				)
				(justify mirror)
			)
		)
		(property "Author" "Antmicro"
			(at 0 0 0)
			(unlocked yes)
			(layer "B.Fab")
			(hide yes)
			(effects
				(font
					(size 1 1)
					(thickness 0.15)
				)
				(justify mirror)
			)
		)
		(property "License" "Apache-2.0"
			(at 0 0 0)
			(unlocked yes)
			(layer "B.Fab")
			(hide yes)
			(effects
				(font
					(size 1 1)
					(thickness 0.15)
				)
				(justify mirror)
			)
		)
		(sheetname "/Power/")
		(sheetfile "power.kicad_sch")
		(attr exclude_from_pos_files exclude_from_bom)
		(fp_circle
			(center 0 0)
			(end 0.475 0)
			(stroke
				(width 0.05)
				(type default)
			)
			(fill no)
			(layer "B.CrtYd")
		)
		(pad "1" smd circle
			(at 0 0 180)
			(size 0.75 0.75)
			(layers "B.Cu" "B.Mask")
			(net 303 "/Power/+VCCD_OUT")
			(pinfunction "1")
			(pintype "passive")
		)
	)
)
